(kicad_pcb
	(version 20260206)
	(generator "pcbnew")
	(generator_version "10.0")
	(general
		(thickness 1.6)
		(legacy_teardrops no)
	)
	(paper "A4")
	(title_block
		(title "9052_F0T_PDB_Converter_Brick_F_V03_1208_1600_OCP.brd")
		(comment 1 "Grand Teton / footprints 148-155 of 578")
	)
	(layers
		(0 "F.Cu" signal "TOP")
		(4 "In1.Cu" signal "GND")
		(6 "In2.Cu" signal "IN1")
		(8 "In3.Cu" signal "GND1")
		(10 "In4.Cu" signal "VCC")
		(12 "In5.Cu" signal "VCC1")
		(14 "In6.Cu" signal "GND2")
		(16 "In7.Cu" signal "IN2")
		(18 "In8.Cu" signal "GND3")
		(2 "B.Cu" signal "BOTTOM")
		(9 "F.Adhes" user "F.Adhesive")
		(11 "B.Adhes" user "B.Adhesive")
		(13 "F.Paste" user "Package Geometry/Pastemask Top")
		(15 "B.Paste" user "Package Geometry/Pastemask Bottom")
		(5 "F.SilkS" user "Ref Des/Silkscreen Top")
		(7 "B.SilkS" user "Ref Des/Silkscreen Bottom")
		(1 "F.Mask" user "Board Geometry/Soldermask Top")
		(3 "B.Mask" user "Board Geometry/Soldermask Bottom")
		(17 "Dwgs.User" user "User.Drawings")
		(19 "Cmts.User" user "User.Comments")
		(21 "Eco1.User" user "User.Eco1")
		(23 "Eco2.User" user "User.Eco2")
		(25 "Edge.Cuts" user "Board Geometry/Outline")
		(27 "Margin" user)
		(31 "F.CrtYd" user "Package Geometry/Place Bound Top")
		(29 "B.CrtYd" user "Package Geometry/Place Bound Bottom")
		(35 "F.Fab" user "Ref Des/Assembly Top")
		(33 "B.Fab" user "Ref Des/Assembly Bottom")
	)
	(footprint ""
		(layer "F.Cu")
		(at 270.383 -69.428868 -90)
		(property "Reference" "PR16"
			(at 0 0 270)
			(layer "F.SilkS")
			(hide yes)
			(effects
				(font
					(size 1.27 1.27)
				)
			)
		)
		(property "Value" ""
			(at 0 0 270)
			(layer "F.Fab")
			(effects
				(font
					(size 1.27 1.27)
				)
			)
		)
		(duplicate_pad_numbers_are_jumpers no)
		(fp_line
			(start -1.2954 0.5842)
			(end -1.2954 -0.5842)
			(stroke
				(width 0.1524)
				(type default)
			)
			(layer "F.SilkS")
		)
		(fp_line
			(start 1.2954 0.5842)
			(end -1.2954 0.5842)
			(stroke
				(width 0.1524)
				(type default)
			)
			(layer "F.SilkS")
		)
		(fp_line
			(start -1.2954 -0.5842)
			(end 1.2954 -0.5842)
			(stroke
				(width 0.1524)
				(type default)
			)
			(layer "F.SilkS")
		)
		(fp_line
			(start 1.2954 -0.5842)
			(end 1.2954 0.5842)
			(stroke
				(width 0.1524)
				(type default)
			)
			(layer "F.SilkS")
		)
		(fp_line
			(start -0.8636 0.4572)
			(end -0.8636 0.4318)
			(stroke
				(width 0.1)
				(type default)
			)
			(layer "F.Fab")
		)
		(fp_line
			(start 0.8636 0.4572)
			(end -0.8636 0.4572)
			(stroke
				(width 0.1)
				(type default)
			)
			(layer "F.Fab")
		)
		(fp_line
			(start -0.8636 0.4318)
			(end -0.8636 0.4064)
			(stroke
				(width 0.1)
				(type default)
			)
			(layer "F.Fab")
		)
		(fp_line
			(start -1.1938 0.4064)
			(end -1.1938 -0.406654)
			(stroke
				(width 0.1)
				(type default)
			)
			(layer "F.Fab")
		)
		(fp_line
			(start -0.8636 0.4064)
			(end -1.1938 0.4064)
			(stroke
				(width 0.1)
				(type default)
			)
			(layer "F.Fab")
		)
		(fp_line
			(start 0.8636 0.4064)
			(end 0.8636 0.4572)
			(stroke
				(width 0.1)
				(type default)
			)
			(layer "F.Fab")
		)
		(fp_line
			(start 1.1938 0.4064)
			(end 0.8636 0.4064)
			(stroke
				(width 0.1)
				(type default)
			)
			(layer "F.Fab")
		)
		(fp_line
			(start -1.1938 -0.406654)
			(end -0.8636 -0.406654)
			(stroke
				(width 0.1)
				(type default)
			)
			(layer "F.Fab")
		)
		(fp_line
			(start -0.8636 -0.406654)
			(end -0.8636 -0.4572)
			(stroke
				(width 0.1)
				(type default)
			)
			(layer "F.Fab")
		)
		(fp_line
			(start 0.8636 -0.406654)
			(end 1.1938 -0.406654)
			(stroke
				(width 0.1)
				(type default)
			)
			(layer "F.Fab")
		)
		(fp_line
			(start 1.1938 -0.406654)
			(end 1.1938 0.4064)
			(stroke
				(width 0.1)
				(type default)
			)
			(layer "F.Fab")
		)
		(fp_line
			(start -0.8636 -0.4572)
			(end 0.8636 -0.4572)
			(stroke
				(width 0.1)
				(type default)
			)
			(layer "F.Fab")
		)
		(fp_line
			(start 0.8636 -0.4572)
			(end 0.8636 -0.406654)
			(stroke
				(width 0.1)
				(type default)
			)
			(layer "F.Fab")
		)
		(pad "1" smd rect
			(at -0.7366 0 180)
			(size 0.7112 0.8128)
			(layers "F.Cu" "F.Mask" "F.Paste")
			(net "P52V_HS1_GATE2_R")
		)
		(pad "2" smd rect
			(at 0.7366 0 180)
			(size 0.7112 0.8128)
			(layers "F.Cu" "F.Mask" "F.Paste")
			(net "P52V_HS1_GATE6")
		)
	)
	(footprint ""
		(layer "F.Cu")
		(at 230.000048 -11.999976 -90)
		(property "Reference" "H18"
			(at -6.134354 12.322048 0)
			(unlocked yes)
			(layer "F.SilkS")
			(effects
				(font
					(size 0.7874 0.5842)
					(thickness 0.1524)
				)
				(justify left)
			)
		)
		(property "Value" ""
			(at 0 0 270)
			(layer "F.Fab")
			(effects
				(font
					(size 1.27 1.27)
				)
			)
		)
		(duplicate_pad_numbers_are_jumpers no)
		(pad "1" thru_hole oval
			(at 0 0 270)
			(size 10.0076 32.004)
			(drill 3.0226
				(offset 0 10.999978)
			)
			(layers "*.Cu" "*.Mask")
			(remove_unused_layers no)
			(net "GND")
			(clearance -1.995678)
			(padstack
				(mode front_inner_back)
				(layer "Inner"
					(shape circle)
					(size 0 0)
					(clearance 0)
				)
				(layer "B.Cu"
					(shape oval)
					(size 10.0076 32.004)
					(offset 0 10.999978)
					(clearance -1.995678)
				)
			)
		)
	)
	(footprint ""
		(layer "F.Cu")
		(at 176.906174 -127.889)
		(property "Reference" "PC118"
			(at 0 0 0)
			(layer "F.SilkS")
			(hide yes)
			(effects
				(font
					(size 1.27 1.27)
				)
			)
		)
		(property "Value" ""
			(at 0 0 0)
			(layer "F.Fab")
			(effects
				(font
					(size 1.27 1.27)
				)
			)
		)
		(duplicate_pad_numbers_are_jumpers no)
		(fp_line
			(start -2.2098 -0.9398)
			(end 2.2098 -0.9398)
			(stroke
				(width 0.1524)
				(type default)
			)
			(layer "F.SilkS")
		)
		(fp_line
			(start -2.2098 0.9398)
			(end -2.2098 -0.9398)
			(stroke
				(width 0.1524)
				(type default)
			)
			(layer "F.SilkS")
		)
		(fp_line
			(start 2.2098 -0.9398)
			(end 2.2098 0.9398)
			(stroke
				(width 0.1524)
				(type default)
			)
			(layer "F.SilkS")
		)
		(fp_line
			(start 2.2098 0.9398)
			(end -2.2098 0.9398)
			(stroke
				(width 0.1524)
				(type default)
			)
			(layer "F.SilkS")
		)
		(fp_line
			(start -1.700022 -0.899922)
			(end 1.700022 -0.899922)
			(stroke
				(width 0.1)
				(type default)
			)
			(layer "F.Fab")
		)
		(fp_line
			(start -1.700022 0.899922)
			(end -1.700022 -0.899922)
			(stroke
				(width 0.1)
				(type default)
			)
			(layer "F.Fab")
		)
		(fp_line
			(start 1.700022 -0.899922)
			(end 1.700022 0.899922)
			(stroke
				(width 0.1)
				(type default)
			)
			(layer "F.Fab")
		)
		(fp_line
			(start 1.700022 0.899922)
			(end -1.700022 0.899922)
			(stroke
				(width 0.1)
				(type default)
			)
			(layer "F.Fab")
		)
		(pad "1" smd rect
			(at -1.4732 0 180)
			(size 1.1684 1.5748)
			(layers "F.Cu" "F.Mask" "F.Paste")
			(net "P52V_HS_FILTER")
		)
		(pad "2" smd rect
			(at 1.4732 0 180)
			(size 1.1684 1.5748)
			(layers "F.Cu" "F.Mask" "F.Paste")
			(net "GND")
		)
	)
	(footprint ""
		(layer "F.Cu")
		(at 21.02993 -25.329896 -90)
		(property "Reference" "J15"
			(at -6.393434 -8.43407 0)
			(unlocked yes)
			(layer "F.SilkS")
			(effects
				(font
					(size 0.7874 0.5842)
					(thickness 0.1524)
				)
				(justify left)
			)
		)
		(property "Value" ""
			(at 0 0 270)
			(layer "F.Fab")
			(effects
				(font
					(size 1.27 1.27)
				)
			)
		)
		(duplicate_pad_numbers_are_jumpers no)
		(fp_line
			(start -5.32511 21.299932)
			(end -5.32511 -10.500106)
			(stroke
				(width 0.1524)
				(type default)
			)
			(layer "F.SilkS")
		)
		(fp_line
			(start 5.32511 21.299932)
			(end -5.32511 21.299932)
			(stroke
				(width 0.1524)
				(type default)
			)
			(layer "F.SilkS")
		)
		(fp_line
			(start -5.32511 10.6299)
			(end 5.32511 10.6299)
			(stroke
				(width 0.1524)
				(type default)
			)
			(layer "F.SilkS")
		)
		(fp_line
			(start -5.32511 -10.500106)
			(end 5.32511 -10.500106)
			(stroke
				(width 0.1524)
				(type default)
			)
			(layer "F.SilkS")
		)
		(fp_line
			(start 5.32511 -10.500106)
			(end 5.32511 21.299932)
			(stroke
				(width 0.1524)
				(type default)
			)
			(layer "F.SilkS")
		)
		(fp_line
			(start -5.32511 21.299932)
			(end -5.32511 -10.500106)
			(stroke
				(width 0.1)
				(type default)
			)
			(layer "F.Fab")
		)
		(fp_line
			(start 5.32511 21.299932)
			(end -5.32511 21.299932)
			(stroke
				(width 0.1)
				(type default)
			)
			(layer "F.Fab")
		)
		(fp_line
			(start -5.32511 -10.500106)
			(end 5.32511 -10.500106)
			(stroke
				(width 0.1)
				(type default)
			)
			(layer "F.Fab")
		)
		(fp_line
			(start 5.32511 -10.500106)
			(end 5.32511 21.299932)
			(stroke
				(width 0.1)
				(type default)
			)
			(layer "F.Fab")
		)
		(pad "" np_thru_hole circle
			(at 0 -6.620002 270)
			(size 3.9624 3.9624)
			(drill 3.9624)
			(layers "*.Cu" "*.Mask")
			(clearance 0.381)
			(thermal_gap 0.381)
		)
		(pad "" np_thru_hole circle
			(at 0 0 270)
			(size 0 0)
			(drill 3.9624)
			(layers "*.Cu" "*.Mask")
			(clearance 0)
		)
		(pad "" np_thru_hole circle
			(at 0 5.62991 270)
			(size 3.9624 3.9624)
			(drill 3.9624)
			(layers "*.Cu" "*.Mask")
			(clearance 0.381)
			(thermal_gap 0.381)
		)
		(zone
			(layers "F.Cu" "B.Cu" "In1.Cu" "In2.Cu" "In3.Cu" "In4.Cu" "In5.Cu" "In6.Cu"
				"In7.Cu" "In8.Cu"
			)
			(hatch none 0.5)
			(connect_pads
				(clearance 0)
			)
			(min_thickness 0.25)
			(keepout
				(tracks not_allowed)
				(vias allowed)
				(pads allowed)
				(copperpour not_allowed)
				(footprints allowed)
			)
			(placement
				(enabled no)
				(sheetname "")
			)
			(fill
				(thermal_gap 0.5)
				(thermal_bridge_width 0.5)
				(island_removal_mode 0)
			)
			(polygon
				(pts
					(arc
						(start 17.88922 -25.329896)
						(mid 12.91082 -25.329896)
						(end 17.88922 -25.329896)
					)
				)
			)
		)
		(zone
			(layers "F.Cu" "B.Cu" "In1.Cu" "In2.Cu" "In3.Cu" "In4.Cu" "In5.Cu" "In6.Cu"
				"In7.Cu" "In8.Cu"
			)
			(hatch none 0.5)
			(connect_pads
				(clearance 0)
			)
			(min_thickness 0.25)
			(keepout
				(tracks not_allowed)
				(vias allowed)
				(pads allowed)
				(copperpour not_allowed)
				(footprints allowed)
			)
			(placement
				(enabled no)
				(sheetname "")
			)
			(fill
				(thermal_gap 0.5)
				(thermal_bridge_width 0.5)
				(island_removal_mode 0)
			)
			(polygon
				(pts
					(arc
						(start 30.139132 -25.329896)
						(mid 25.160732 -25.329896)
						(end 30.139132 -25.329896)
					)
				)
			)
		)
		(zone
			(layers "F.Cu" "B.Cu" "In1.Cu" "In2.Cu" "In3.Cu" "In4.Cu" "In5.Cu" "In6.Cu"
				"In7.Cu" "In8.Cu"
			)
			(hatch none 0.5)
			(connect_pads
				(clearance 0)
			)
			(min_thickness 0.25)
			(keepout
				(tracks not_allowed)
				(vias allowed)
				(pads allowed)
				(copperpour not_allowed)
				(footprints allowed)
			)
			(placement
				(enabled no)
				(sheetname "")
			)
			(fill
				(thermal_gap 0.5)
				(thermal_bridge_width 0.5)
				(island_removal_mode 0)
			)
			(polygon
				(pts
					(arc
						(start 25.04313 -25.329896)
						(mid 17.01673 -25.329896)
						(end 25.04313 -25.329896)
					)
				)
			)
		)
	)
	(footprint ""
		(layer "F.Cu")
		(at 224.917 -95.504 -90)
		(property "Reference" "C31"
			(at 0 0 270)
			(layer "F.SilkS")
			(hide yes)
			(effects
				(font
					(size 1.27 1.27)
				)
			)
		)
		(property "Value" ""
			(at 0 0 270)
			(layer "F.Fab")
			(effects
				(font
					(size 1.27 1.27)
				)
			)
		)
		(duplicate_pad_numbers_are_jumpers no)
		(fp_line
			(start -2.2098 0.9398)
			(end -2.2098 -0.9398)
			(stroke
				(width 0.1524)
				(type default)
			)
			(layer "F.SilkS")
		)
		(fp_line
			(start 2.2098 0.9398)
			(end -2.2098 0.9398)
			(stroke
				(width 0.1524)
				(type default)
			)
			(layer "F.SilkS")
		)
		(fp_line
			(start -2.2098 -0.9398)
			(end 2.2098 -0.9398)
			(stroke
				(width 0.1524)
				(type default)
			)
			(layer "F.SilkS")
		)
		(fp_line
			(start 2.2098 -0.9398)
			(end 2.2098 0.9398)
			(stroke
				(width 0.1524)
				(type default)
			)
			(layer "F.SilkS")
		)
		(fp_line
			(start -1.700022 0.899922)
			(end -1.700022 -0.899922)
			(stroke
				(width 0.1)
				(type default)
			)
			(layer "F.Fab")
		)
		(fp_line
			(start 1.700022 0.899922)
			(end -1.700022 0.899922)
			(stroke
				(width 0.1)
				(type default)
			)
			(layer "F.Fab")
		)
		(fp_line
			(start -1.700022 -0.899922)
			(end 1.700022 -0.899922)
			(stroke
				(width 0.1)
				(type default)
			)
			(layer "F.Fab")
		)
		(fp_line
			(start 1.700022 -0.899922)
			(end 1.700022 0.899922)
			(stroke
				(width 0.1)
				(type default)
			)
			(layer "F.Fab")
		)
		(pad "1" smd rect
			(at -1.4732 0 90)
			(size 1.1684 1.5748)
			(layers "F.Cu" "F.Mask" "F.Paste")
			(net "P52V_HS")
		)
		(pad "2" smd rect
			(at 1.4732 0 90)
			(size 1.1684 1.5748)
			(layers "F.Cu" "F.Mask" "F.Paste")
			(net "GND")
		)
	)
	(footprint ""
		(layer "F.Cu")
		(at 209.931 -85.725)
		(property "Reference" "R63"
			(at 0 0 0)
			(layer "F.SilkS")
			(hide yes)
			(effects
				(font
					(size 1.27 1.27)
				)
			)
		)
		(property "Value" ""
			(at 0 0 0)
			(layer "F.Fab")
			(effects
				(font
					(size 1.27 1.27)
				)
			)
		)
		(duplicate_pad_numbers_are_jumpers no)
		(fp_line
			(start -2.234946 -0.9271)
			(end 2.234946 -0.9271)
			(stroke
				(width 0.1524)
				(type default)
			)
			(layer "F.SilkS")
		)
		(fp_line
			(start -2.234946 0.9271)
			(end -2.234946 -0.9271)
			(stroke
				(width 0.1524)
				(type default)
			)
			(layer "F.SilkS")
		)
		(fp_line
			(start 2.234946 -0.9271)
			(end 2.234946 0.9271)
			(stroke
				(width 0.1524)
				(type default)
			)
			(layer "F.SilkS")
		)
		(fp_line
			(start 2.234946 0.9271)
			(end -2.234946 0.9271)
			(stroke
				(width 0.1524)
				(type default)
			)
			(layer "F.SilkS")
		)
		(fp_line
			(start -1.575054 -0.824992)
			(end -1.575054 0.824992)
			(stroke
				(width 0.1)
				(type default)
			)
			(layer "F.Fab")
		)
		(fp_line
			(start -1.575054 0.824992)
			(end 1.575054 0.824992)
			(stroke
				(width 0.1)
				(type default)
			)
			(layer "F.Fab")
		)
		(fp_line
			(start 1.575054 -0.824992)
			(end -1.575054 -0.824992)
			(stroke
				(width 0.1)
				(type default)
			)
			(layer "F.Fab")
		)
		(fp_line
			(start 1.575054 0.824992)
			(end 1.575054 -0.824992)
			(stroke
				(width 0.1)
				(type default)
			)
			(layer "F.Fab")
		)
		(pad "1" smd rect
			(at -1.599946 0)
			(size 1.016 1.6002)
			(layers "F.Cu" "F.Mask" "F.Paste")
			(net "LED_D1_R4")
		)
		(pad "2" smd rect
			(at 1.599946 0)
			(size 1.016 1.6002)
			(layers "F.Cu" "F.Mask" "F.Paste")
			(net "LED_D1_R5")
		)
	)
	(footprint ""
		(layer "F.Cu")
		(at 162.687 -51.816)
		(property "Reference" "PC34"
			(at 0 0 0)
			(layer "F.SilkS")
			(hide yes)
			(effects
				(font
					(size 1.27 1.27)
				)
			)
		)
		(property "Value" ""
			(at 0 0 0)
			(layer "F.Fab")
			(effects
				(font
					(size 1.27 1.27)
				)
			)
		)
		(duplicate_pad_numbers_are_jumpers no)
		(fp_line
			(start -1.524 -0.762)
			(end 1.524 -0.762)
			(stroke
				(width 0.1524)
				(type default)
			)
			(layer "F.SilkS")
		)
		(fp_line
			(start -1.524 0.762)
			(end -1.524 -0.762)
			(stroke
				(width 0.1524)
				(type default)
			)
			(layer "F.SilkS")
		)
		(fp_line
			(start 1.524 -0.762)
			(end 1.524 0.762)
			(stroke
				(width 0.1524)
				(type default)
			)
			(layer "F.SilkS")
		)
		(fp_line
			(start 1.524 0.762)
			(end -1.524 0.762)
			(stroke
				(width 0.1524)
				(type default)
			)
			(layer "F.SilkS")
		)
		(fp_line
			(start -1.1049 -0.724916)
			(end -1.1049 0.724916)
			(stroke
				(width 0.1)
				(type default)
			)
			(layer "F.Fab")
		)
		(fp_line
			(start -1.1049 0.724916)
			(end 1.1049 0.724916)
			(stroke
				(width 0.1)
				(type default)
			)
			(layer "F.Fab")
		)
		(fp_line
			(start 1.1049 -0.724916)
			(end -1.1049 -0.724916)
			(stroke
				(width 0.1)
				(type default)
			)
			(layer "F.Fab")
		)
		(fp_line
			(start 1.1049 0.724916)
			(end 1.1049 -0.724916)
			(stroke
				(width 0.1)
				(type default)
			)
			(layer "F.Fab")
		)
		(pad "1" smd rect
			(at -0.889 0 180)
			(size 1.016 1.27)
			(layers "F.Cu" "F.Mask" "F.Paste")
			(net "P12V_BRICK")
		)
		(pad "2" smd rect
			(at 0.889 0 180)
			(size 1.016 1.27)
			(layers "F.Cu" "F.Mask" "F.Paste")
			(net "GND")
		)
	)
	(footprint ""
		(layer "F.Cu")
		(at 172.0596 -12.4968 90)
		(property "Reference" "PC101"
			(at 0 0 90)
			(layer "F.SilkS")
			(hide yes)
			(effects
				(font
					(size 1.27 1.27)
				)
			)
		)
		(property "Value" ""
			(at 0 0 90)
			(layer "F.Fab")
			(effects
				(font
					(size 1.27 1.27)
				)
			)
		)
		(duplicate_pad_numbers_are_jumpers no)
		(fp_line
			(start 1.524 -0.762)
			(end 1.524 0.762)
			(stroke
				(width 0.1524)
				(type default)
			)
			(layer "F.SilkS")
		)
		(fp_line
			(start -1.524 -0.762)
			(end 1.524 -0.762)
			(stroke
				(width 0.1524)
				(type default)
			)
			(layer "F.SilkS")
		)
		(fp_line
			(start 1.524 0.762)
			(end -1.524 0.762)
			(stroke
				(width 0.1524)
				(type default)
			)
			(layer "F.SilkS")
		)
		(fp_line
			(start -1.524 0.762)
			(end -1.524 -0.762)
			(stroke
				(width 0.1524)
				(type default)
			)
			(layer "F.SilkS")
		)
		(fp_line
			(start 1.1049 -0.724916)
			(end -1.1049 -0.724916)
			(stroke
				(width 0.1)
				(type default)
			)
			(layer "F.Fab")
		)
		(fp_line
			(start -1.1049 -0.724916)
			(end -1.1049 0.724916)
			(stroke
				(width 0.1)
				(type default)
			)
			(layer "F.Fab")
		)
		(fp_line
			(start 1.1049 0.724916)
			(end 1.1049 -0.724916)
			(stroke
				(width 0.1)
				(type default)
			)
			(layer "F.Fab")
		)
		(fp_line
			(start -1.1049 0.724916)
			(end 1.1049 0.724916)
			(stroke
				(width 0.1)
				(type default)
			)
			(layer "F.Fab")
		)
		(pad "1" smd rect
			(at -0.889 0 270)
			(size 1.016 1.27)
			(layers "F.Cu" "F.Mask" "F.Paste")
			(net "SW_P12V_FILT__P3V3_AUX")
		)
		(pad "2" smd rect
			(at 0.889 0 270)
			(size 1.016 1.27)
			(layers "F.Cu" "F.Mask" "F.Paste")
			(net "GND")
		)
	)
)
